Created on Valor NPI 9.6 Update 2 - Netlist Compare Summary.
DATE :  09 Jun 2017
TIME :  18:13:47


     MISMATCH SUMMARY REPORT
     -----------------------

Job  : 16315-1                 Job  : 16315-1
Step : q                       Step : q
Type : CAD                     Type : CURCAD

-----------------------------------------------

 Mismatch Type: shorted

   GND                   -   NET00000            
   AGND_CURRENT_MONOA    -    "                  
   AGND_CURRENT_DPB      -    "                  
   AGND_CURRENT_MONOB    -    "                  
   AGND_P5V_A            -    "                  
   AGND_P5V_B            -    "                  
   AGND_P3V3_STBY        -    "                  
   AGND_P5V_C            -    "                  
   AGND_P5V_D            -    "                  
   P3V3_STBY_A           -   NET00026            
   P3V3_STBY_CC          -    "                  
   P5V_A_2               -   NET00041            
   P5V_B_CC              -    "                  
   P5V_A_4               -   NET00593            
   P5V_D_CC              -    "                  
   P5V_A_1               -   NET00887            
   P5V_A_CC              -    "                  
   P5V_A_3               -   NET00888            
   P5V_C_CC              -    "                  

 Total : 6
-----------------------------------------------

 Mismatch Type: broken


 Total : 0
-----------------------------------------------

 Mismatch Type: missing


 Total : 0
-----------------------------------------------

 Mismatch Type: extra


 Total : 0
-----------------------------------------------
